# T6G (Grand Teton) — schematic netlist excerpt (pin names and nets, part order shuffled) for the footprints in the layout excerpt that follows; sources: Cadence DE-HDL packaged netlist, KiCad conversion of 04192023_DAF0TMB3IC0_F0TG_MB_C_brd_V02_OCP.brd

R6768  Q_RES  1K 1% CHIP  pkg 0201LF  page 184 : A = P1V8_CPU0_RT_1D ; B = SMB_RT_CPU0_P2_R_SDA
C400  Q_CAP  0.1UF 10V 10% X7S  pkg C0201  page 345 : A = P0V9_CPU1_RT2_2A ; B = GND
C3926  Q_CAP  22UF 4V 20% X6S  pkg C0402  page 70 : A = PVDDCR_SOC_P0 ; B = GND

(kicad_pcb
	(version 20260206)
	(generator "pcbnew")
	(generator_version "10.0")
	(general
		(thickness 1.6)
		(legacy_teardrops no)
	)
	(paper "A4")
	(title_block
		(title "04192023_DAF0TMB3IC0_F0TG_MB_C_brd_V02_OCP.brd")
		(comment 1 "Grand Teton / footprints 7085-7087 of 8354")
	)
	(layers
		(0 "F.Cu" signal "TOP")
		(4 "In1.Cu" signal "GND")
		(6 "In2.Cu" signal "IN1")
		(8 "In3.Cu" signal "GND1")
		(10 "In4.Cu" signal "IN2")
		(12 "In5.Cu" signal "GND2")
		(14 "In6.Cu" signal "IN3")
		(16 "In7.Cu" signal "GND3")
		(18 "In8.Cu" signal "VCC")
		(20 "In9.Cu" signal "VCC1")
		(22 "In10.Cu" signal "GND4")
		(24 "In11.Cu" signal "IN4")
		(26 "In12.Cu" signal "GND5")
		(28 "In13.Cu" signal "IN5")
		(30 "In14.Cu" signal "GND6")
		(32 "In15.Cu" signal "IN6")
		(34 "In16.Cu" signal "GND7")
		(2 "B.Cu" signal "BOTTOM")
		(9 "F.Adhes" user "F.Adhesive")
		(11 "B.Adhes" user "B.Adhesive")
		(13 "F.Paste" user "Package Geometry/Pastemask Top")
		(15 "B.Paste" user "Package Geometry/Pastemask Bottom")
		(5 "F.SilkS" user "Ref Des/Silkscreen Top")
		(7 "B.SilkS" user "Ref Des/Silkscreen Bottom")
		(1 "F.Mask" user "Board Geometry/Soldermask Top")
		(3 "B.Mask" user "Board Geometry/Soldermask Bottom")
		(17 "Dwgs.User" user "User.Drawings")
		(19 "Cmts.User" user "User.Comments")
		(21 "Eco1.User" user "User.Eco1")
		(23 "Eco2.User" user "User.Eco2")
		(25 "Edge.Cuts" user "Board Geometry/Outline")
		(27 "Margin" user)
		(31 "F.CrtYd" user "Package Geometry/Place Bound Top")
		(29 "B.CrtYd" user "Package Geometry/Place Bound Bottom")
		(35 "F.Fab" user "Ref Des/Assembly Top")
		(33 "B.Fab" user "Ref Des/Assembly Bottom")
	)
	(footprint ""
		(layer "B.Cu")
		(at 162.746182 -388.011162 -90)
		(property "Reference" "C400"
			(at 0 0 90)
			(layer "B.SilkS")
			(hide yes)
			(effects
				(font
					(size 1.27 1.27)
				)
				(justify mirror)
			)
		)
		(property "Value" ""
			(at 0 0 90)
			(layer "B.Fab")
			(effects
				(font
					(size 1.27 1.27)
				)
				(justify mirror)
			)
		)
		(duplicate_pad_numbers_are_jumpers no)
		(fp_line
			(start -0.299974 0.150114)
			(end 0.299974 0.150114)
			(stroke
				(width 0.1)
				(type default)
			)
			(layer "B.Fab")
		)
		(fp_line
			(start 0.299974 0.150114)
			(end 0.299974 -0.150114)
			(stroke
				(width 0.1)
				(type default)
			)
			(layer "B.Fab")
		)
		(fp_line
			(start -0.299974 -0.150114)
			(end -0.299974 0.150114)
			(stroke
				(width 0.1)
				(type default)
			)
			(layer "B.Fab")
		)
		(fp_line
			(start 0.299974 -0.150114)
			(end -0.299974 -0.150114)
			(stroke
				(width 0.1)
				(type default)
			)
			(layer "B.Fab")
		)
		(pad "1" smd rect
			(at 0.2667 0 90)
			(size 0.3048 0.381)
			(layers "B.Cu" "B.Mask" "B.Paste")
			(net "P0V9_CPU1_RT2_2A")
		)
		(pad "2" smd rect
			(at -0.2667 0 90)
			(size 0.3048 0.381)
			(layers "B.Cu" "B.Mask" "B.Paste")
			(net "GND")
		)
	)
	(footprint ""
		(layer "B.Cu")
		(at 361.046014 -258.795012 180)
		(property "Reference" "C3926"
			(at 0 0 0)
			(layer "B.SilkS")
			(hide yes)
			(effects
				(font
					(size 1.27 1.27)
				)
				(justify mirror)
			)
		)
		(property "Value" ""
			(at 0 0 0)
			(layer "B.Fab")
			(effects
				(font
					(size 1.27 1.27)
				)
				(justify mirror)
			)
		)
		(duplicate_pad_numbers_are_jumpers no)
		(fp_line
			(start 0.7874 0.4064)
			(end 0.7874 -0.4064)
			(stroke
				(width 0.1524)
				(type default)
			)
			(layer "B.SilkS")
		)
		(fp_line
			(start 0.7874 -0.4064)
			(end -0.7874 -0.4064)
			(stroke
				(width 0.1524)
				(type default)
			)
			(layer "B.SilkS")
		)
		(fp_line
			(start -0.7874 0.4064)
			(end 0.7874 0.4064)
			(stroke
				(width 0.1524)
				(type default)
			)
			(layer "B.SilkS")
		)
		(fp_line
			(start -0.7874 -0.4064)
			(end -0.7874 0.4064)
			(stroke
				(width 0.1524)
				(type default)
			)
			(layer "B.SilkS")
		)
		(fp_line
			(start 0.67945 0.3048)
			(end 0.67945 -0.305054)
			(stroke
				(width 0.1)
				(type default)
			)
			(layer "B.Fab")
		)
		(fp_line
			(start 0.67945 -0.305054)
			(end 0.12065 -0.305054)
			(stroke
				(width 0.1)
				(type default)
			)
			(layer "B.Fab")
		)
		(fp_line
			(start 0.12065 0.3048)
			(end 0.67945 0.3048)
			(stroke
				(width 0.1)
				(type default)
			)
			(layer "B.Fab")
		)
		(fp_line
			(start 0.12065 0.2794)
			(end 0.12065 0.3048)
			(stroke
				(width 0.1)
				(type default)
			)
			(layer "B.Fab")
		)
		(fp_line
			(start 0.12065 -0.2794)
			(end -0.12065 -0.2794)
			(stroke
				(width 0.1)
				(type default)
			)
			(layer "B.Fab")
		)
		(fp_line
			(start 0.12065 -0.305054)
			(end 0.12065 -0.2794)
			(stroke
				(width 0.1)
				(type default)
			)
			(layer "B.Fab")
		)
		(fp_line
			(start -0.120396 0.3048)
			(end -0.120396 0.2794)
			(stroke
				(width 0.1)
				(type default)
			)
			(layer "B.Fab")
		)
		(fp_line
			(start -0.120396 0.2794)
			(end 0.12065 0.2794)
			(stroke
				(width 0.1)
				(type default)
			)
			(layer "B.Fab")
		)
		(fp_line
			(start -0.12065 -0.2794)
			(end -0.12065 -0.3048)
			(stroke
				(width 0.1)
				(type default)
			)
			(layer "B.Fab")
		)
		(fp_line
			(start -0.12065 -0.3048)
			(end -0.67945 -0.3048)
			(stroke
				(width 0.1)
				(type default)
			)
			(layer "B.Fab")
		)
		(fp_line
			(start -0.67945 0.3048)
			(end -0.120396 0.3048)
			(stroke
				(width 0.1)
				(type default)
			)
			(layer "B.Fab")
		)
		(fp_line
			(start -0.67945 -0.3048)
			(end -0.67945 0.3048)
			(stroke
				(width 0.1)
				(type default)
			)
			(layer "B.Fab")
		)
		(pad "1" smd circle
			(at 0.40005 0)
			(size 0 0)
			(layers "B.Cu" "B.Mask" "B.Paste")
			(net "PVDDCR_SOC_P0")
		)
		(pad "2" smd circle
			(at -0.40005 0)
			(size 0 0)
			(layers "B.Cu" "B.Mask" "B.Paste")
			(net "GND")
		)
	)
	(footprint ""
		(layer "B.Cu")
		(at 232.537 -335.153 90)
		(property "Reference" "R6768"
			(at 0 0 90)
			(layer "B.SilkS")
			(hide yes)
			(effects
				(font
					(size 1.27 1.27)
				)
				(justify mirror)
			)
		)
		(property "Value" ""
			(at 0 0 90)
			(layer "B.Fab")
			(effects
				(font
					(size 1.27 1.27)
				)
				(justify mirror)
			)
		)
		(duplicate_pad_numbers_are_jumpers no)
		(fp_line
			(start 0.32512 -0.175006)
			(end -0.32512 -0.175006)
			(stroke
				(width 0.1)
				(type default)
			)
			(layer "B.Fab")
		)
		(fp_line
			(start -0.32512 -0.175006)
			(end -0.32512 0.175006)
			(stroke
				(width 0.1)
				(type default)
			)
			(layer "B.Fab")
		)
		(fp_line
			(start 0.32512 0.175006)
			(end 0.32512 -0.175006)
			(stroke
				(width 0.1)
				(type default)
			)
			(layer "B.Fab")
		)
		(fp_line
			(start -0.32512 0.175006)
			(end 0.32512 0.175006)
			(stroke
				(width 0.1)
				(type default)
			)
			(layer "B.Fab")
		)
		(pad "1" smd rect
			(at 0.2667 0 270)
			(size 0.3048 0.381)
			(layers "B.Cu" "B.Mask" "B.Paste")
			(net "P1V8_CPU0_RT_1D")
		)
		(pad "2" smd rect
			(at -0.2667 0 90)
			(size 0.3048 0.381)
			(layers "B.Cu" "B.Mask" "B.Paste")
			(net "SMB_RT_CPU0_P2_R_SDA")
		)
	)
)
